(kicad_pcb
	(version 20260206)
	(generator "pcbnew")
	(generator_version "10.0")
	(general
		(thickness 1.6)
		(legacy_teardrops no)
	)
	(paper "A4")
	(title_block
		(title "Wiwynn_Tioga_Pass_MB.brd")
		(comment 1 "Tioga Pass / footprints 2268-2275 of 4770")
	)
	(layers
		(0 "F.Cu" signal "TOP")
		(4 "In1.Cu" signal "L2GND")
		(6 "In2.Cu" signal "L3")
		(8 "In3.Cu" signal "L4GND")
		(10 "In4.Cu" signal "L5")
		(12 "In5.Cu" signal "L6GND")
		(14 "In6.Cu" signal "L7VCC")
		(16 "In7.Cu" signal "L8VCC")
		(18 "In8.Cu" signal "L9GND")
		(20 "In9.Cu" signal "L10")
		(22 "In10.Cu" signal "L11GND")
		(24 "In11.Cu" signal "L12")
		(26 "In12.Cu" signal "L13GND")
		(2 "B.Cu" signal "BOTTOM")
		(9 "F.Adhes" user "F.Adhesive")
		(11 "B.Adhes" user "B.Adhesive")
		(13 "F.Paste" user "Package Geometry/Pastemask Top")
		(15 "B.Paste" user "Package Geometry/Pastemask Bottom")
		(5 "F.SilkS" user "Ref Des/Silkscreen Top")
		(7 "B.SilkS" user "Ref Des/Silkscreen Bottom")
		(1 "F.Mask" user "Board Geometry/Soldermask Top")
		(3 "B.Mask" user "Board Geometry/Soldermask Bottom")
		(17 "Dwgs.User" user "User.Drawings")
		(19 "Cmts.User" user "User.Comments")
		(21 "Eco1.User" user "User.Eco1")
		(23 "Eco2.User" user "User.Eco2")
		(25 "Edge.Cuts" user "Board Geometry/Outline")
		(27 "Margin" user)
		(31 "F.CrtYd" user "Package Geometry/Place Bound Top")
		(29 "B.CrtYd" user "Package Geometry/Place Bound Bottom")
		(35 "F.Fab" user "Ref Des/Assembly Top")
		(33 "B.Fab" user "Ref Des/Assembly Bottom")
	)
	(footprint ""
		(layer "F.Cu")
		(at 465.328 -0.254 -90)
		(property "Reference" "R9G26"
			(at 0 0 270)
			(layer "F.SilkS")
			(hide yes)
			(effects
				(font
					(size 1.27 1.27)
				)
			)
		)
		(property "Value" ""
			(at 0 0 270)
			(layer "F.Fab")
			(effects
				(font
					(size 1.27 1.27)
				)
			)
		)
		(duplicate_pad_numbers_are_jumpers no)
		(fp_poly
			(pts
				(xy -0.2794 -0.1016) (xy 0.2794 -0.1016) (xy 0.2794 0.9906) (xy -0.2794 0.9906)
			)
			(stroke
				(width 0)
				(type default)
			)
			(fill no)
			(layer "F.CrtYd")
		)
		(fp_line
			(start -0.2794 0.9906)
			(end 0.2794 0.9906)
			(stroke
				(width 0.1)
				(type default)
			)
			(layer "F.Fab")
		)
		(fp_line
			(start 0.2794 0.9906)
			(end 0.2794 -0.1016)
			(stroke
				(width 0.1)
				(type default)
			)
			(layer "F.Fab")
		)
		(fp_line
			(start -0.2794 -0.1016)
			(end -0.2794 0.9906)
			(stroke
				(width 0.1)
				(type default)
			)
			(layer "F.Fab")
		)
		(fp_line
			(start 0.2794 -0.1016)
			(end -0.2794 -0.1016)
			(stroke
				(width 0.1)
				(type default)
			)
			(layer "F.Fab")
		)
		(pad "1" smd rect
			(at 0 0 270)
			(size 0.508 0.508)
			(layers "F.Cu" "F.Mask" "F.Paste")
			(net "A_P3V_BAT_SCALED")
		)
		(pad "2" smd rect
			(at 0 0.889 270)
			(size 0.508 0.508)
			(layers "F.Cu" "F.Mask" "F.Paste")
			(net "GND")
		)
		(zone
			(layer "F.Cu")
			(hatch none 0.5)
			(connect_pads
				(clearance 0)
			)
			(min_thickness 0.25)
			(keepout
				(tracks not_allowed)
				(vias allowed)
				(pads allowed)
				(copperpour not_allowed)
				(footprints allowed)
			)
			(placement
				(enabled no)
				(sheetname "")
			)
			(fill
				(thermal_gap 0.5)
				(thermal_bridge_width 0.5)
				(island_removal_mode 0)
			)
			(polygon
				(pts
					(xy 464.693 -0.508) (xy 464.693 0) (xy 465.074 0) (xy 465.074 -0.508)
				)
			)
		)
		(zone
			(layer "F.Cu")
			(hatch none 0.5)
			(connect_pads
				(clearance 0)
			)
			(min_thickness 0.25)
			(keepout
				(tracks allowed)
				(vias not_allowed)
				(pads allowed)
				(copperpour not_allowed)
				(footprints allowed)
			)
			(placement
				(enabled no)
				(sheetname "")
			)
			(fill
				(thermal_gap 0.5)
				(thermal_bridge_width 0.5)
				(island_removal_mode 0)
			)
			(polygon
				(pts
					(xy 465.074 -0.508) (xy 465.074 0) (xy 464.693 0) (xy 464.693 -0.508)
				)
			)
		)
	)
	(footprint ""
		(layer "F.Cu")
		(at 178.943 -131.7625)
		(property "Reference" "C4B8"
			(at 0 0 0)
			(layer "F.SilkS")
			(hide yes)
			(effects
				(font
					(size 1.27 1.27)
				)
			)
		)
		(property "Value" ""
			(at 0 0 0)
			(layer "F.Fab")
			(effects
				(font
					(size 1.27 1.27)
				)
			)
		)
		(duplicate_pad_numbers_are_jumpers no)
		(fp_poly
			(pts
				(xy 0.3048 -0.1016) (xy 0.3048 0.9906) (xy -0.3048 0.9906) (xy -0.3048 -0.1016)
			)
			(stroke
				(width 0)
				(type default)
			)
			(fill no)
			(layer "F.CrtYd")
		)
		(fp_line
			(start -0.3048 -0.1016)
			(end -0.3048 0.9906)
			(stroke
				(width 0.1)
				(type default)
			)
			(layer "F.Fab")
		)
		(fp_line
			(start -0.3048 0.9906)
			(end 0.3048 0.9906)
			(stroke
				(width 0.1)
				(type default)
			)
			(layer "F.Fab")
		)
		(fp_line
			(start 0.3048 -0.1016)
			(end -0.3048 -0.1016)
			(stroke
				(width 0.1)
				(type default)
			)
			(layer "F.Fab")
		)
		(fp_line
			(start 0.3048 0.9906)
			(end 0.3048 -0.1016)
			(stroke
				(width 0.1)
				(type default)
			)
			(layer "F.Fab")
		)
		(pad "1" smd rect
			(at 0 0)
			(size 0.508 0.508)
			(layers "F.Cu" "F.Mask" "F.Paste")
			(net "PWRGD_PVPP_KLM_R")
		)
		(pad "2" smd rect
			(at 0 0.889)
			(size 0.508 0.508)
			(layers "F.Cu" "F.Mask" "F.Paste")
			(net "GND")
		)
		(zone
			(layer "F.Cu")
			(hatch none 0.5)
			(connect_pads
				(clearance 0)
			)
			(min_thickness 0.25)
			(keepout
				(tracks allowed)
				(vias not_allowed)
				(pads allowed)
				(copperpour not_allowed)
				(footprints allowed)
			)
			(placement
				(enabled no)
				(sheetname "")
			)
			(fill
				(thermal_gap 0.5)
				(thermal_bridge_width 0.5)
				(island_removal_mode 0)
			)
			(polygon
				(pts
					(xy 178.689 -131.5085) (xy 179.197 -131.5085) (xy 179.197 -131.1275) (xy 178.689 -131.1275)
				)
			)
		)
		(zone
			(layer "F.Cu")
			(hatch none 0.5)
			(connect_pads
				(clearance 0)
			)
			(min_thickness 0.25)
			(keepout
				(tracks not_allowed)
				(vias allowed)
				(pads allowed)
				(copperpour not_allowed)
				(footprints allowed)
			)
			(placement
				(enabled no)
				(sheetname "")
			)
			(fill
				(thermal_gap 0.5)
				(thermal_bridge_width 0.5)
				(island_removal_mode 0)
			)
			(polygon
				(pts
					(xy 178.689 -131.1275) (xy 179.197 -131.1275) (xy 179.197 -131.5085) (xy 178.689 -131.5085)
				)
			)
		)
	)
	(footprint ""
		(layer "F.Cu")
		(at 476.4659 -147.4089 -90)
		(property "Reference" "C1L9"
			(at 0 0 270)
			(layer "F.SilkS")
			(hide yes)
			(effects
				(font
					(size 1.27 1.27)
				)
			)
		)
		(property "Value" ""
			(at 0 0 270)
			(layer "F.Fab")
			(effects
				(font
					(size 1.27 1.27)
				)
			)
		)
		(duplicate_pad_numbers_are_jumpers no)
		(fp_poly
			(pts
				(xy 0.3048 -0.1016) (xy 0.3048 0.9906) (xy -0.3048 0.9906) (xy -0.3048 -0.1016)
			)
			(stroke
				(width 0)
				(type default)
			)
			(fill no)
			(layer "F.CrtYd")
		)
		(fp_line
			(start -0.3048 0.9906)
			(end 0.3048 0.9906)
			(stroke
				(width 0.1)
				(type default)
			)
			(layer "F.Fab")
		)
		(fp_line
			(start 0.3048 0.9906)
			(end 0.3048 -0.1016)
			(stroke
				(width 0.1)
				(type default)
			)
			(layer "F.Fab")
		)
		(fp_line
			(start -0.3048 -0.1016)
			(end -0.3048 0.9906)
			(stroke
				(width 0.1)
				(type default)
			)
			(layer "F.Fab")
		)
		(fp_line
			(start 0.3048 -0.1016)
			(end -0.3048 -0.1016)
			(stroke
				(width 0.1)
				(type default)
			)
			(layer "F.Fab")
		)
		(pad "1" smd rect
			(at 0 0 270)
			(size 0.508 0.508)
			(layers "F.Cu" "F.Mask" "F.Paste")
			(net "P3V3_STBY")
		)
		(pad "2" smd rect
			(at 0 0.889 270)
			(size 0.508 0.508)
			(layers "F.Cu" "F.Mask" "F.Paste")
			(net "GND")
		)
		(zone
			(layer "F.Cu")
			(hatch none 0.5)
			(connect_pads
				(clearance 0)
			)
			(min_thickness 0.25)
			(keepout
				(tracks not_allowed)
				(vias allowed)
				(pads allowed)
				(copperpour not_allowed)
				(footprints allowed)
			)
			(placement
				(enabled no)
				(sheetname "")
			)
			(fill
				(thermal_gap 0.5)
				(thermal_bridge_width 0.5)
				(island_removal_mode 0)
			)
			(polygon
				(pts
					(xy 475.8309 -147.6629) (xy 475.8309 -147.1549) (xy 476.2119 -147.1549) (xy 476.2119 -147.6629)
				)
			)
		)
		(zone
			(layer "F.Cu")
			(hatch none 0.5)
			(connect_pads
				(clearance 0)
			)
			(min_thickness 0.25)
			(keepout
				(tracks allowed)
				(vias not_allowed)
				(pads allowed)
				(copperpour not_allowed)
				(footprints allowed)
			)
			(placement
				(enabled no)
				(sheetname "")
			)
			(fill
				(thermal_gap 0.5)
				(thermal_bridge_width 0.5)
				(island_removal_mode 0)
			)
			(polygon
				(pts
					(xy 476.2119 -147.6629) (xy 476.2119 -147.1549) (xy 475.8309 -147.1549) (xy 475.8309 -147.6629)
				)
			)
		)
	)
	(footprint ""
		(layer "F.Cu")
		(at 351.731834 -21.284438)
		(property "Reference" "R12W2"
			(at 0 0 0)
			(layer "F.SilkS")
			(hide yes)
			(effects
				(font
					(size 1.27 1.27)
				)
			)
		)
		(property "Value" "*"
			(at 0 -8.9535 0)
			(unlocked yes)
			(layer "F.Fab")
			(hide yes)
			(effects
				(font
					(size 1.27 1.016)
					(thickness 0.1524)
				)
			)
		)
		(property "Device Type" "665KR5B-1-GP_SMD-RG3-665KR5B-1A"
			(at 0 -10.6299 0)
			(unlocked yes)
			(layer "F.Fab")
			(hide yes)
			(effects
				(font
					(size 1.27 1.016)
					(thickness 0.1524)
				)
			)
		)
		(duplicate_pad_numbers_are_jumpers no)
		(fp_line
			(start -0.889 -1.7018)
			(end -0.889 0.2794)
			(stroke
				(width 0.1524)
				(type default)
			)
			(layer "F.SilkS")
		)
		(fp_line
			(start -0.889 0.0762)
			(end -0.889 1.7018)
			(stroke
				(width 0.1524)
				(type default)
			)
			(layer "F.SilkS")
		)
		(fp_line
			(start -0.889 1.7018)
			(end 0.889 1.7018)
			(stroke
				(width 0.1524)
				(type default)
			)
			(layer "F.SilkS")
		)
		(fp_line
			(start 0.889 -1.7018)
			(end -0.889 -1.7018)
			(stroke
				(width 0.1524)
				(type default)
			)
			(layer "F.SilkS")
		)
		(fp_line
			(start 0.889 -1.7018)
			(end 0.889 -0.381)
			(stroke
				(width 0.1524)
				(type default)
			)
			(layer "F.SilkS")
		)
		(fp_line
			(start 0.889 1.7018)
			(end 0.889 -0.508)
			(stroke
				(width 0.1524)
				(type default)
			)
			(layer "F.SilkS")
		)
		(fp_poly
			(pts
				(xy 0.9652 -1.778) (xy 0.9652 1.778) (xy -0.9652 1.778) (xy -0.9652 -1.778)
			)
			(stroke
				(width 0)
				(type default)
			)
			(fill no)
			(layer "F.CrtYd")
		)
		(fp_rect
			(start -0.9652 1.778)
			(end 0.9652 -1.778)
			(stroke
				(width 0)
				(type default)
			)
			(fill no)
			(layer "F.Fab")
		)
		(pad "1" smd rect
			(at 0 -0.9652)
			(size 1.397 1.143)
			(layers "F.Cu" "F.Mask" "F.Paste")
			(net "P12V_NVDIMM_ABC_D")
		)
		(pad "2" smd rect
			(at 0 0.9652)
			(size 1.397 1.143)
			(layers "F.Cu" "F.Mask" "F.Paste")
			(net "VR_PVDDQ_ABC_VINSEN")
		)
	)
	(footprint ""
		(layer "F.Cu")
		(at 450.215 -21.209 -90)
		(property "Reference" "R9W32"
			(at -0.8382 -0.67818 270)
			(unlocked yes)
			(layer "F.SilkS")
			(effects
				(font
					(size 0.4064 0.254)
					(thickness 0.1524)
				)
				(justify left)
			)
		)
		(property "Value" ""
			(at 0 0 270)
			(layer "F.Fab")
			(effects
				(font
					(size 1.27 1.27)
				)
			)
		)
		(duplicate_pad_numbers_are_jumpers no)
		(fp_poly
			(pts
				(xy -0.2794 -0.1016) (xy 0.2794 -0.1016) (xy 0.2794 0.9906) (xy -0.2794 0.9906)
			)
			(stroke
				(width 0)
				(type default)
			)
			(fill no)
			(layer "F.CrtYd")
		)
		(fp_line
			(start -0.2794 0.9906)
			(end 0.2794 0.9906)
			(stroke
				(width 0.1)
				(type default)
			)
			(layer "F.Fab")
		)
		(fp_line
			(start 0.2794 0.9906)
			(end 0.2794 -0.1016)
			(stroke
				(width 0.1)
				(type default)
			)
			(layer "F.Fab")
		)
		(fp_line
			(start -0.2794 -0.1016)
			(end -0.2794 0.9906)
			(stroke
				(width 0.1)
				(type default)
			)
			(layer "F.Fab")
		)
		(fp_line
			(start 0.2794 -0.1016)
			(end -0.2794 -0.1016)
			(stroke
				(width 0.1)
				(type default)
			)
			(layer "F.Fab")
		)
		(pad "1" smd rect
			(at 0 0 270)
			(size 0.508 0.508)
			(layers "F.Cu" "F.Mask" "F.Paste")
			(net "VR_P2V5_BMC_STBY_FB")
		)
		(pad "2" smd rect
			(at 0 0.889 270)
			(size 0.508 0.508)
			(layers "F.Cu" "F.Mask" "F.Paste")
			(net "GND")
		)
		(zone
			(layer "F.Cu")
			(hatch none 0.5)
			(connect_pads
				(clearance 0)
			)
			(min_thickness 0.25)
			(keepout
				(tracks not_allowed)
				(vias allowed)
				(pads allowed)
				(copperpour not_allowed)
				(footprints allowed)
			)
			(placement
				(enabled no)
				(sheetname "")
			)
			(fill
				(thermal_gap 0.5)
				(thermal_bridge_width 0.5)
				(island_removal_mode 0)
			)
			(polygon
				(pts
					(xy 449.58 -21.463) (xy 449.58 -20.955) (xy 449.961 -20.955) (xy 449.961 -21.463)
				)
			)
		)
		(zone
			(layer "F.Cu")
			(hatch none 0.5)
			(connect_pads
				(clearance 0)
			)
			(min_thickness 0.25)
			(keepout
				(tracks allowed)
				(vias not_allowed)
				(pads allowed)
				(copperpour not_allowed)
				(footprints allowed)
			)
			(placement
				(enabled no)
				(sheetname "")
			)
			(fill
				(thermal_gap 0.5)
				(thermal_bridge_width 0.5)
				(island_removal_mode 0)
			)
			(polygon
				(pts
					(xy 449.961 -21.463) (xy 449.961 -20.955) (xy 449.58 -20.955) (xy 449.58 -21.463)
				)
			)
		)
	)
	(footprint ""
		(layer "F.Cu")
		(at 332.90002 -118.5164 90)
		(property "Reference" "C6B19"
			(at -0.8382 -0.67818 90)
			(unlocked yes)
			(layer "F.SilkS")
			(effects
				(font
					(size 0.4064 0.254)
					(thickness 0.1524)
				)
				(justify left)
			)
		)
		(property "Value" ""
			(at 0 0 90)
			(layer "F.Fab")
			(effects
				(font
					(size 1.27 1.27)
				)
			)
		)
		(duplicate_pad_numbers_are_jumpers no)
		(fp_poly
			(pts
				(xy 0.3048 -0.1016) (xy 0.3048 0.9906) (xy -0.3048 0.9906) (xy -0.3048 -0.1016)
			)
			(stroke
				(width 0)
				(type default)
			)
			(fill no)
			(layer "F.CrtYd")
		)
		(fp_line
			(start 0.3048 -0.1016)
			(end -0.3048 -0.1016)
			(stroke
				(width 0.1)
				(type default)
			)
			(layer "F.Fab")
		)
		(fp_line
			(start -0.3048 -0.1016)
			(end -0.3048 0.9906)
			(stroke
				(width 0.1)
				(type default)
			)
			(layer "F.Fab")
		)
		(fp_line
			(start 0.3048 0.9906)
			(end 0.3048 -0.1016)
			(stroke
				(width 0.1)
				(type default)
			)
			(layer "F.Fab")
		)
		(fp_line
			(start -0.3048 0.9906)
			(end 0.3048 0.9906)
			(stroke
				(width 0.1)
				(type default)
			)
			(layer "F.Fab")
		)
		(pad "1" smd rect
			(at 0 0 90)
			(size 0.508 0.508)
			(layers "F.Cu" "F.Mask" "F.Paste")
			(net "P3E_CPU0_PE1_PCH_TXN<8>")
		)
		(pad "2" smd rect
			(at 0 0.889 90)
			(size 0.508 0.508)
			(layers "F.Cu" "F.Mask" "F.Paste")
			(net "P3E_CPU0_PE1_PCH_C_TXN<8>")
		)
		(zone
			(layer "F.Cu")
			(hatch none 0.5)
			(connect_pads
				(clearance 0)
			)
			(min_thickness 0.25)
			(keepout
				(tracks allowed)
				(vias not_allowed)
				(pads allowed)
				(copperpour not_allowed)
				(footprints allowed)
			)
			(placement
				(enabled no)
				(sheetname "")
			)
			(fill
				(thermal_gap 0.5)
				(thermal_bridge_width 0.5)
				(island_removal_mode 0)
			)
			(polygon
				(pts
					(xy 333.15402 -118.2624) (xy 333.15402 -118.7704) (xy 333.53502 -118.7704) (xy 333.53502 -118.2624)
				)
			)
		)
		(zone
			(layer "F.Cu")
			(hatch none 0.5)
			(connect_pads
				(clearance 0)
			)
			(min_thickness 0.25)
			(keepout
				(tracks not_allowed)
				(vias allowed)
				(pads allowed)
				(copperpour not_allowed)
				(footprints allowed)
			)
			(placement
				(enabled no)
				(sheetname "")
			)
			(fill
				(thermal_gap 0.5)
				(thermal_bridge_width 0.5)
				(island_removal_mode 0)
			)
			(polygon
				(pts
					(xy 333.53502 -118.2624) (xy 333.53502 -118.7704) (xy 333.15402 -118.7704) (xy 333.15402 -118.2624)
				)
			)
		)
	)
	(footprint ""
		(layer "F.Cu")
		(at 157.988 -120.080786 90)
		(property "Reference" "R3B2"
			(at 0 0 90)
			(layer "F.SilkS")
			(hide yes)
			(effects
				(font
					(size 1.27 1.27)
				)
			)
		)
		(property "Value" ""
			(at 0 0 90)
			(layer "F.Fab")
			(effects
				(font
					(size 1.27 1.27)
				)
			)
		)
		(duplicate_pad_numbers_are_jumpers no)
		(fp_poly
			(pts
				(xy -0.2794 -0.1016) (xy 0.2794 -0.1016) (xy 0.2794 0.9906) (xy -0.2794 0.9906)
			)
			(stroke
				(width 0)
				(type default)
			)
			(fill no)
			(layer "F.CrtYd")
		)
		(fp_line
			(start 0.2794 -0.1016)
			(end -0.2794 -0.1016)
			(stroke
				(width 0.1)
				(type default)
			)
			(layer "F.Fab")
		)
		(fp_line
			(start -0.2794 -0.1016)
			(end -0.2794 0.9906)
			(stroke
				(width 0.1)
				(type default)
			)
			(layer "F.Fab")
		)
		(fp_line
			(start 0.2794 0.9906)
			(end 0.2794 -0.1016)
			(stroke
				(width 0.1)
				(type default)
			)
			(layer "F.Fab")
		)
		(fp_line
			(start -0.2794 0.9906)
			(end 0.2794 0.9906)
			(stroke
				(width 0.1)
				(type default)
			)
			(layer "F.Fab")
		)
		(pad "1" smd rect
			(at 0 0 90)
			(size 0.508 0.508)
			(layers "F.Cu" "F.Mask" "F.Paste")
			(net "SVID_ALERT0_CPU1_R_N")
		)
		(pad "2" smd rect
			(at 0 0.889 90)
			(size 0.508 0.508)
			(layers "F.Cu" "F.Mask" "F.Paste")
			(net "PVCCIO_CPU1")
		)
		(zone
			(layer "F.Cu")
			(hatch none 0.5)
			(connect_pads
				(clearance 0)
			)
			(min_thickness 0.25)
			(keepout
				(tracks allowed)
				(vias not_allowed)
				(pads allowed)
				(copperpour not_allowed)
				(footprints allowed)
			)
			(placement
				(enabled no)
				(sheetname "")
			)
			(fill
				(thermal_gap 0.5)
				(thermal_bridge_width 0.5)
				(island_removal_mode 0)
			)
			(polygon
				(pts
					(xy 158.242 -119.826786) (xy 158.242 -120.334786) (xy 158.623 -120.334786) (xy 158.623 -119.826786)
				)
			)
		)
		(zone
			(layer "F.Cu")
			(hatch none 0.5)
			(connect_pads
				(clearance 0)
			)
			(min_thickness 0.25)
			(keepout
				(tracks not_allowed)
				(vias allowed)
				(pads allowed)
				(copperpour not_allowed)
				(footprints allowed)
			)
			(placement
				(enabled no)
				(sheetname "")
			)
			(fill
				(thermal_gap 0.5)
				(thermal_bridge_width 0.5)
				(island_removal_mode 0)
			)
			(polygon
				(pts
					(xy 158.623 -119.826786) (xy 158.623 -120.334786) (xy 158.242 -120.334786) (xy 158.242 -119.826786)
				)
			)
		)
	)
	(footprint ""
		(layer "F.Cu")
		(at 274.5232 -79.6036 180)
		(property "Reference" "C5D22"
			(at 0 0 180)
			(layer "F.SilkS")
			(hide yes)
			(effects
				(font
					(size 1.27 1.27)
				)
			)
		)
		(property "Value" ""
			(at 0 0 180)
			(layer "F.Fab")
			(effects
				(font
					(size 1.27 1.27)
				)
			)
		)
		(duplicate_pad_numbers_are_jumpers no)
		(fp_poly
			(pts
				(xy -0.4953 -0.2032) (xy 0.4953 -0.2032) (xy 0.4953 1.6002) (xy -0.4953 1.6002)
			)
			(stroke
				(width 0)
				(type default)
			)
			(fill no)
			(layer "F.CrtYd")
		)
		(fp_line
			(start 0.4953 1.6002)
			(end -0.4953 1.6002)
			(stroke
				(width 0.1)
				(type default)
			)
			(layer "F.Fab")
		)
		(fp_line
			(start 0.4953 -0.2032)
			(end 0.4953 1.6002)
			(stroke
				(width 0.1)
				(type default)
			)
			(layer "F.Fab")
		)
		(fp_line
			(start -0.4953 1.6002)
			(end -0.4953 -0.2032)
			(stroke
				(width 0.1)
				(type default)
			)
			(layer "F.Fab")
		)
		(fp_line
			(start -0.4953 -0.2032)
			(end 0.4953 -0.2032)
			(stroke
				(width 0.1)
				(type default)
			)
			(layer "F.Fab")
		)
		(pad "1" smd rect
			(at 0 0 180)
			(size 0.762 0.889)
			(layers "F.Cu" "F.Mask" "F.Paste")
			(net "PVCCMCP_CPU0")
		)
		(pad "2" smd rect
			(at 0 1.397 180)
			(size 0.762 0.889)
			(layers "F.Cu" "F.Mask" "F.Paste")
			(net "GND")
		)
		(zone
			(layer "F.Cu")
			(hatch none 0.5)
			(connect_pads
				(clearance 0)
			)
			(min_thickness 0.25)
			(keepout
				(tracks not_allowed)
				(vias allowed)
				(pads allowed)
				(copperpour not_allowed)
				(footprints allowed)
			)
			(placement
				(enabled no)
				(sheetname "")
			)
			(fill
				(thermal_gap 0.5)
				(thermal_bridge_width 0.5)
				(island_removal_mode 0)
			)
			(polygon
				(pts
					(xy 274.9042 -80.0481) (xy 274.1422 -80.0481) (xy 274.1422 -80.5561) (xy 274.9042 -80.5561)
				)
			)
		)
	)
)
